# S9S_MB_2U (Grand Teton) — schematic netlist excerpt (pin names and nets, part order shuffled) for the footprints in the layout excerpt that follows; sources: Cadence DE-HDL packaged netlist, KiCad conversion of 03242023_DA0F0TMBIJ0_F0T_Motherboard_J_brd_V01_OCP.brd

PD112  SCHOTTKY_AC  B340A-13-F IC  pkg D2010XF  page 192 : A = GND ; C = P12V_E1S_0
U1_BP  TP  NA  pkg TP_BOM ONLY  page 312 : TP = NC

(kicad_pcb
	(version 20260206)
	(generator "pcbnew")
	(generator_version "10.0")
	(general
		(thickness 1.6)
		(legacy_teardrops no)
	)
	(paper "A4")
	(title_block
		(title "03242023_DA0F0TMBIJ0_F0T_Motherboard_J_brd_V01_OCP.brd")
		(comment 1 "Grand Teton / footprints 4015-4016 of 6105")
	)
	(layers
		(0 "F.Cu" signal "TOP")
		(4 "In1.Cu" signal "GND")
		(6 "In2.Cu" signal "IN1")
		(8 "In3.Cu" signal "GND1")
		(10 "In4.Cu" signal "IN2")
		(12 "In5.Cu" signal "GND2")
		(14 "In6.Cu" signal "IN3")
		(16 "In7.Cu" signal "GND3")
		(18 "In8.Cu" signal "VCC")
		(20 "In9.Cu" signal "VCC1")
		(22 "In10.Cu" signal "GND4")
		(24 "In11.Cu" signal "IN4")
		(26 "In12.Cu" signal "GND5")
		(28 "In13.Cu" signal "IN5")
		(30 "In14.Cu" signal "GND6")
		(32 "In15.Cu" signal "IN6")
		(34 "In16.Cu" signal "GND7")
		(2 "B.Cu" signal "BOTTOM")
		(9 "F.Adhes" user "F.Adhesive")
		(11 "B.Adhes" user "B.Adhesive")
		(13 "F.Paste" user "Package Geometry/Pastemask Top")
		(15 "B.Paste" user "Package Geometry/Pastemask Bottom")
		(5 "F.SilkS" user "Ref Des/Silkscreen Top")
		(7 "B.SilkS" user "Ref Des/Silkscreen Bottom")
		(1 "F.Mask" user "Board Geometry/Soldermask Top")
		(3 "B.Mask" user "Board Geometry/Soldermask Bottom")
		(17 "Dwgs.User" user "User.Drawings")
		(19 "Cmts.User" user "User.Comments")
		(21 "Eco1.User" user "User.Eco1")
		(23 "Eco2.User" user "User.Eco2")
		(25 "Edge.Cuts" user "Board Geometry/Outline")
		(27 "Margin" user)
		(31 "F.CrtYd" user "Package Geometry/Place Bound Top")
		(29 "B.CrtYd" user "Package Geometry/Place Bound Bottom")
		(35 "F.Fab" user "Ref Des/Assembly Top")
		(33 "B.Fab" user "Ref Des/Assembly Bottom")
	)
	(footprint ""
		(layer "F.Cu")
		(at 246.14505 -40.259762 90)
		(property "Reference" "PD112"
			(at 7.442454 -2.35839 0)
			(unlocked yes)
			(layer "F.SilkS")
			(effects
				(font
					(size 0.7874 0.5842)
					(thickness 0.1524)
				)
				(justify left)
			)
		)
		(property "Value" ""
			(at 0 0 90)
			(layer "F.Fab")
			(effects
				(font
					(size 1.27 1.27)
				)
			)
		)
		(duplicate_pad_numbers_are_jumpers no)
		(fp_line
			(start 4.107942 -1.459992)
			(end 4.107942 1.459992)
			(stroke
				(width 0.1524)
				(type default)
			)
			(layer "F.SilkS")
		)
		(fp_line
			(start -3.400044 -1.459992)
			(end 4.107942 -1.459992)
			(stroke
				(width 0.1524)
				(type default)
			)
			(layer "F.SilkS")
		)
		(fp_line
			(start 4.107942 1.459992)
			(end -3.400044 1.459992)
			(stroke
				(width 0.1524)
				(type default)
			)
			(layer "F.SilkS")
		)
		(fp_line
			(start -3.400044 1.459992)
			(end -3.400044 -1.459992)
			(stroke
				(width 0.1524)
				(type default)
			)
			(layer "F.SilkS")
		)
		(fp_rect
			(start 3.308096 -1.459992)
			(end 4.107942 1.459992)
			(stroke
				(width 0)
				(type default)
			)
			(fill yes)
			(layer "F.SilkS")
		)
		(fp_line
			(start 2.29997 -1.459992)
			(end 2.29997 1.459992)
			(stroke
				(width 0.1)
				(type default)
			)
			(layer "F.Fab")
		)
		(fp_line
			(start -2.29997 -1.459992)
			(end 2.29997 -1.459992)
			(stroke
				(width 0.1)
				(type default)
			)
			(layer "F.Fab")
		)
		(fp_line
			(start 2.29997 1.459992)
			(end -2.29997 1.459992)
			(stroke
				(width 0.1)
				(type default)
			)
			(layer "F.Fab")
		)
		(fp_line
			(start -2.29997 1.459992)
			(end -2.29997 -1.459992)
			(stroke
				(width 0.1)
				(type default)
			)
			(layer "F.Fab")
		)
		(fp_text user "+"
			(at -4.7752 -0.12065 90)
			(unlocked yes)
			(layer "F.SilkS")
			(effects
				(font
					(size 1.905 1.4224)
					(thickness 0.1524)
				)
				(justify left)
			)
		)
		(fp_text user "-"
			(at 5.4102 0.29845 270)
			(unlocked yes)
			(layer "F.SilkS")
			(effects
				(font
					(size 1.905 1.4224)
					(thickness 0.1524)
				)
				(justify left)
			)
		)
		(fp_text user "+"
			(at -4.7752 -0.12065 90)
			(unlocked yes)
			(layer "F.Fab")
			(effects
				(font
					(size 1.905 1.4224)
					(thickness 0.1524)
				)
				(justify left)
			)
		)
		(fp_text user "-"
			(at 5.4102 0.29845 270)
			(unlocked yes)
			(layer "F.Fab")
			(effects
				(font
					(size 1.905 1.4224)
					(thickness 0.1524)
				)
				(justify left)
			)
		)
		(pad "A" smd rect
			(at -1.999996 0 180)
			(size 1.7018 2.5146)
			(layers "F.Cu" "F.Mask" "F.Paste")
			(net "GND")
		)
		(pad "C" smd rect
			(at 1.999996 0 180)
			(size 1.7018 2.5146)
			(layers "F.Cu" "F.Mask" "F.Paste")
			(net "P12V_E1S_0")
		)
	)
	(footprint ""
		(layer "F.Cu")
		(at 492.16437 -470.73439)
		(property "Reference" "U1_BP"
			(at -0.18669 -3.567938 0)
			(unlocked yes)
			(layer "F.SilkS")
			(effects
				(font
					(size 0.7874 0.5842)
					(thickness 0.1524)
				)
				(justify left)
			)
		)
		(property "Value" ""
			(at 0 0 0)
			(layer "F.Fab")
			(effects
				(font
					(size 1.27 1.27)
				)
			)
		)
		(duplicate_pad_numbers_are_jumpers no)
		(pad "1" smd circle
			(at 0 0)
			(size 0.762 0.762)
			(layers "F.Cu" "F.Mask" "F.Paste")
			(net "Net_8487")
		)
	)
)
